# S9S_MB_2U (Grand Teton) — schematic netlist excerpt (pin names and nets, part order shuffled) for the footprints in the layout excerpt that follows; sources: Cadence DE-HDL packaged netlist, KiCad conversion of 03242023_DA0F0TMBIJ0_F0T_Motherboard_J_brd_V01_OCP.brd

C1338  Q_CAP  10UF 16V 10% EMPTY  pkg C0805  page 260 : A = P3V3_AUX ; B = GND
R615  Q_RES  1K 1% CHIP  pkg 0402LF  page 199 : A = P3V3_AUX ; B = FM_PCH_VISA_DEFAULT

(kicad_pcb
	(version 20260206)
	(generator "pcbnew")
	(generator_version "10.0")
	(general
		(thickness 1.6)
		(legacy_teardrops no)
	)
	(paper "A4")
	(title_block
		(title "03242023_DA0F0TMBIJ0_F0T_Motherboard_J_brd_V01_OCP.brd")
		(comment 1 "Grand Teton / footprints 2143-2144 of 6105")
	)
	(layers
		(0 "F.Cu" signal "TOP")
		(4 "In1.Cu" signal "GND")
		(6 "In2.Cu" signal "IN1")
		(8 "In3.Cu" signal "GND1")
		(10 "In4.Cu" signal "IN2")
		(12 "In5.Cu" signal "GND2")
		(14 "In6.Cu" signal "IN3")
		(16 "In7.Cu" signal "GND3")
		(18 "In8.Cu" signal "VCC")
		(20 "In9.Cu" signal "VCC1")
		(22 "In10.Cu" signal "GND4")
		(24 "In11.Cu" signal "IN4")
		(26 "In12.Cu" signal "GND5")
		(28 "In13.Cu" signal "IN5")
		(30 "In14.Cu" signal "GND6")
		(32 "In15.Cu" signal "IN6")
		(34 "In16.Cu" signal "GND7")
		(2 "B.Cu" signal "BOTTOM")
		(9 "F.Adhes" user "F.Adhesive")
		(11 "B.Adhes" user "B.Adhesive")
		(13 "F.Paste" user "Package Geometry/Pastemask Top")
		(15 "B.Paste" user "Package Geometry/Pastemask Bottom")
		(5 "F.SilkS" user "Ref Des/Silkscreen Top")
		(7 "B.SilkS" user "Ref Des/Silkscreen Bottom")
		(1 "F.Mask" user "Board Geometry/Soldermask Top")
		(3 "B.Mask" user "Board Geometry/Soldermask Bottom")
		(17 "Dwgs.User" user "User.Drawings")
		(19 "Cmts.User" user "User.Comments")
		(21 "Eco1.User" user "User.Eco1")
		(23 "Eco2.User" user "User.Eco2")
		(25 "Edge.Cuts" user "Board Geometry/Outline")
		(27 "Margin" user)
		(31 "F.CrtYd" user "Package Geometry/Place Bound Top")
		(29 "B.CrtYd" user "Package Geometry/Place Bound Bottom")
		(35 "F.Fab" user "Ref Des/Assembly Top")
		(33 "B.Fab" user "Ref Des/Assembly Bottom")
	)
	(footprint ""
		(layer "F.Cu")
		(at 441.99048 -51.077368 -90)
		(property "Reference" "C1338"
			(at 0 0 270)
			(layer "F.SilkS")
			(hide yes)
			(effects
				(font
					(size 1.27 1.27)
				)
			)
		)
		(property "Value" ""
			(at 0 0 270)
			(layer "F.Fab")
			(effects
				(font
					(size 1.27 1.27)
				)
			)
		)
		(duplicate_pad_numbers_are_jumpers no)
		(fp_line
			(start -1.524 0.762)
			(end -1.524 -0.762)
			(stroke
				(width 0.1524)
				(type default)
			)
			(layer "F.SilkS")
		)
		(fp_line
			(start 1.524 0.762)
			(end -1.524 0.762)
			(stroke
				(width 0.1524)
				(type default)
			)
			(layer "F.SilkS")
		)
		(fp_line
			(start -1.524 -0.762)
			(end 1.524 -0.762)
			(stroke
				(width 0.1524)
				(type default)
			)
			(layer "F.SilkS")
		)
		(fp_line
			(start 1.524 -0.762)
			(end 1.524 0.762)
			(stroke
				(width 0.1524)
				(type default)
			)
			(layer "F.SilkS")
		)
		(fp_line
			(start -1.1049 0.724916)
			(end 1.1049 0.724916)
			(stroke
				(width 0.1)
				(type default)
			)
			(layer "F.Fab")
		)
		(fp_line
			(start 1.1049 0.724916)
			(end 1.1049 -0.724916)
			(stroke
				(width 0.1)
				(type default)
			)
			(layer "F.Fab")
		)
		(fp_line
			(start -1.1049 -0.724916)
			(end -1.1049 0.724916)
			(stroke
				(width 0.1)
				(type default)
			)
			(layer "F.Fab")
		)
		(fp_line
			(start 1.1049 -0.724916)
			(end -1.1049 -0.724916)
			(stroke
				(width 0.1)
				(type default)
			)
			(layer "F.Fab")
		)
		(pad "1" smd rect
			(at -0.889 0 90)
			(size 1.016 1.27)
			(layers "F.Cu" "F.Mask" "F.Paste")
			(net "P3V3_AUX")
		)
		(pad "2" smd rect
			(at 0.889 0 90)
			(size 1.016 1.27)
			(layers "F.Cu" "F.Mask" "F.Paste")
			(net "GND")
		)
	)
	(footprint ""
		(layer "F.Cu")
		(at 320.190622 -62.880748)
		(property "Reference" "R615"
			(at 0 0 0)
			(layer "F.SilkS")
			(hide yes)
			(effects
				(font
					(size 1.27 1.27)
				)
			)
		)
		(property "Value" ""
			(at 0 0 0)
			(layer "F.Fab")
			(effects
				(font
					(size 1.27 1.27)
				)
			)
		)
		(duplicate_pad_numbers_are_jumpers no)
		(fp_line
			(start -0.7874 -0.4064)
			(end 0.7874 -0.4064)
			(stroke
				(width 0.1524)
				(type default)
			)
			(layer "F.SilkS")
		)
		(fp_line
			(start -0.7874 0.4064)
			(end -0.7874 -0.4064)
			(stroke
				(width 0.1524)
				(type default)
			)
			(layer "F.SilkS")
		)
		(fp_line
			(start 0.7874 -0.4064)
			(end 0.7874 0.4064)
			(stroke
				(width 0.1524)
				(type default)
			)
			(layer "F.SilkS")
		)
		(fp_line
			(start 0.7874 0.4064)
			(end -0.7874 0.4064)
			(stroke
				(width 0.1524)
				(type default)
			)
			(layer "F.SilkS")
		)
		(fp_line
			(start -0.67945 -0.305054)
			(end -0.12065 -0.305054)
			(stroke
				(width 0.1)
				(type default)
			)
			(layer "F.Fab")
		)
		(fp_line
			(start -0.67945 0.3048)
			(end -0.67945 -0.305054)
			(stroke
				(width 0.1)
				(type default)
			)
			(layer "F.Fab")
		)
		(fp_line
			(start -0.12065 -0.305054)
			(end -0.12065 -0.2794)
			(stroke
				(width 0.1)
				(type default)
			)
			(layer "F.Fab")
		)
		(fp_line
			(start -0.12065 -0.2794)
			(end 0.12065 -0.2794)
			(stroke
				(width 0.1)
				(type default)
			)
			(layer "F.Fab")
		)
		(fp_line
			(start -0.12065 0.2794)
			(end -0.12065 0.3048)
			(stroke
				(width 0.1)
				(type default)
			)
			(layer "F.Fab")
		)
		(fp_line
			(start -0.12065 0.3048)
			(end -0.67945 0.3048)
			(stroke
				(width 0.1)
				(type default)
			)
			(layer "F.Fab")
		)
		(fp_line
			(start 0.120396 0.2794)
			(end -0.12065 0.2794)
			(stroke
				(width 0.1)
				(type default)
			)
			(layer "F.Fab")
		)
		(fp_line
			(start 0.120396 0.3048)
			(end 0.120396 0.2794)
			(stroke
				(width 0.1)
				(type default)
			)
			(layer "F.Fab")
		)
		(fp_line
			(start 0.12065 -0.3048)
			(end 0.67945 -0.3048)
			(stroke
				(width 0.1)
				(type default)
			)
			(layer "F.Fab")
		)
		(fp_line
			(start 0.12065 -0.2794)
			(end 0.12065 -0.3048)
			(stroke
				(width 0.1)
				(type default)
			)
			(layer "F.Fab")
		)
		(fp_line
			(start 0.67945 -0.3048)
			(end 0.67945 0.3048)
			(stroke
				(width 0.1)
				(type default)
			)
			(layer "F.Fab")
		)
		(fp_line
			(start 0.67945 0.3048)
			(end 0.120396 0.3048)
			(stroke
				(width 0.1)
				(type default)
			)
			(layer "F.Fab")
		)
		(pad "1" smd circle
			(at -0.40005 0)
			(size 0 0)
			(layers "F.Cu" "F.Mask" "F.Paste")
			(net "P3V3_AUX")
		)
		(pad "2" smd circle
			(at 0.40005 0)
			(size 0 0)
			(layers "F.Cu" "F.Mask" "F.Paste")
			(net "FM_PCH_VISA_DEFAULT")
		)
	)
)
